(kicad_pcb
	(version 20260206)
	(generator "pcbnew")
	(generator_version "10.0")
	(general
		(thickness 1.6)
		(legacy_teardrops no)
	)
	(paper "A4")
	(title_block
		(title "v1-chassis-manager — T6M_CM_d_v01_1031_1645.brd")
		(comment 1 "Open CloudServer (Microsoft) / footprint 105 of 2512 (U129), pads 1-100 of 100")
	)
	(layers
		(0 "F.Cu" signal "TOP")
		(4 "In1.Cu" signal "GND1")
		(6 "In2.Cu" signal "IN1")
		(8 "In3.Cu" signal "VCC1")
		(10 "In4.Cu" signal "VCC2")
		(12 "In5.Cu" signal "GND2")
		(14 "In6.Cu" signal "IN2")
		(16 "In7.Cu" signal "IN3")
		(18 "In8.Cu" signal "GND3")
		(2 "B.Cu" signal "BOTTOM")
		(9 "F.Adhes" user "F.Adhesive")
		(11 "B.Adhes" user "B.Adhesive")
		(13 "F.Paste" user "Package Geometry/Pastemask Top")
		(15 "B.Paste" user "Package Geometry/Pastemask Bottom")
		(5 "F.SilkS" user "Ref Des/Silkscreen Top")
		(7 "B.SilkS" user "Ref Des/Silkscreen Bottom")
		(1 "F.Mask" user "Board Geometry/Soldermask Top")
		(3 "B.Mask" user "Board Geometry/Soldermask Bottom")
		(17 "Dwgs.User" user "User.Drawings")
		(19 "Cmts.User" user "User.Comments")
		(21 "Eco1.User" user "User.Eco1")
		(23 "Eco2.User" user "User.Eco2")
		(25 "Edge.Cuts" user "Board Geometry/Outline")
		(27 "Margin" user)
		(31 "F.CrtYd" user "Package Geometry/Place Bound Top")
		(29 "B.CrtYd" user "Package Geometry/Place Bound Bottom")
		(35 "F.Fab" user "Ref Des/Assembly Top")
		(33 "B.Fab" user "Ref Des/Assembly Bottom")
	)
	(footprint ""
		(layer "F.Cu")
		(at 137.52576 -171.108624 -90)
		(property "Reference" "U129"
			(at -6.558534 12.007088 0)
			(unlocked yes)
			(layer "F.SilkS")
			(effects
				(font
					(size 0.7874 0.5842)
					(thickness 0.1524)
				)
				(justify left)
			)
		)
		(property "Value" ""
			(at 0 0 270)
			(layer "F.Fab")
			(effects
				(font
					(size 1.27 1.27)
				)
			)
		)
		(duplicate_pad_numbers_are_jumpers no)
		(pad "1" smd rect
			(at -7.750048 -5.999988)
			(size 0.2794 1.4986)
			(layers "F.Cu" "F.Mask" "F.Paste")
			(net "CPLD_UART_DTR_P3_N")
		)
		(pad "2" smd rect
			(at -7.750048 -5.500116)
			(size 0.2794 1.4986)
			(layers "F.Cu" "F.Mask" "F.Paste")
			(net "UART_SW_S0_N")
		)
		(pad "3" smd rect
			(at -7.750048 -4.99999)
			(size 0.2794 1.4986)
			(layers "F.Cu" "F.Mask" "F.Paste")
			(net "UART_SW_S1_N")
		)
		(pad "4" smd rect
			(at -7.750048 -4.500118)
			(size 0.2794 1.4986)
			(layers "F.Cu" "F.Mask" "F.Paste")
			(net "UART_SW_S2_N")
		)
		(pad "5" smd rect
			(at -7.750048 -3.999992)
			(size 0.2794 1.4986)
			(layers "F.Cu" "F.Mask" "F.Paste")
			(net "UART_SW_S3_N")
		)
		(pad "6" smd rect
			(at -7.750048 -3.50012)
			(size 0.2794 1.4986)
			(layers "F.Cu" "F.Mask" "F.Paste")
			(net "UART_SW_S4_N")
		)
		(pad "7" smd rect
			(at -7.750048 -2.999994)
			(size 0.2794 1.4986)
			(layers "F.Cu" "F.Mask" "F.Paste")
			(net "UART_SW_S5_N")
		)
		(pad "8" smd rect
			(at -7.750048 -2.500122)
			(size 0.2794 1.4986)
			(layers "F.Cu" "F.Mask" "F.Paste")
			(net "UART3_RESET_N")
		)
		(pad "9" smd rect
			(at -7.750048 -1.999996)
			(size 0.2794 1.4986)
			(layers "F.Cu" "F.Mask" "F.Paste")
			(net "P3V3_NODE1")
		)
		(pad "10" smd rect
			(at -7.750048 -1.500124)
			(size 0.2794 1.4986)
			(layers "F.Cu" "F.Mask" "F.Paste")
			(net "GND")
		)
		(pad "11" smd rect
			(at -7.750048 -0.999998)
			(size 0.2794 1.4986)
			(layers "F.Cu" "F.Mask" "F.Paste")
			(net "GND")
		)
		(pad "12" smd rect
			(at -7.750048 -0.499872)
			(size 0.2794 1.4986)
			(layers "F.Cu" "F.Mask" "F.Paste")
			(net "CPLD_WDT3")
		)
		(pad "13" smd rect
			(at -7.750048 0)
			(size 0.2794 1.4986)
			(layers "F.Cu" "F.Mask" "F.Paste")
			(net "P3V3_NODE1")
		)
		(pad "14" smd rect
			(at -7.750048 0.499872)
			(size 0.2794 1.4986)
			(layers "F.Cu" "F.Mask" "F.Paste")
			(net "CPU_RSV_1")
		)
		(pad "15" smd rect
			(at -7.750048 0.999998)
			(size 0.2794 1.4986)
			(layers "F.Cu" "F.Mask" "F.Paste")
			(net "UART_TX_P4")
		)
		(pad "16" smd rect
			(at -7.750048 1.500124)
			(size 0.2794 1.4986)
			(layers "F.Cu" "F.Mask" "F.Paste")
			(net "UART_RX_P4")
		)
		(pad "17" smd rect
			(at -7.750048 1.999996)
			(size 0.2794 1.4986)
			(layers "F.Cu" "F.Mask" "F.Paste")
			(net "UART_DTR_P3_N")
		)
		(pad "18" smd rect
			(at -7.750048 2.500122)
			(size 0.2794 1.4986)
			(layers "F.Cu" "F.Mask" "F.Paste")
			(net "UART_TX_P3")
		)
		(pad "19" smd rect
			(at -7.750048 2.999994)
			(size 0.2794 1.4986)
			(layers "F.Cu" "F.Mask" "F.Paste")
			(net "UART_RX_P3")
		)
		(pad "20" smd rect
			(at -7.750048 3.50012)
			(size 0.2794 1.4986)
			(layers "F.Cu" "F.Mask" "F.Paste")
			(net "UART_CMC_TX_P")
		)
		(pad "21" smd rect
			(at -7.750048 3.999992)
			(size 0.2794 1.4986)
			(layers "F.Cu" "F.Mask" "F.Paste")
			(net "UART_CMC_RX_P")
		)
		(pad "22" smd rect
			(at -7.750048 4.500118)
			(size 0.2794 1.4986)
			(layers "F.Cu" "F.Mask" "F.Paste")
			(net "JTAG_CPLD3_TMS")
		)
		(pad "23" smd rect
			(at -7.750048 4.99999)
			(size 0.2794 1.4986)
			(layers "F.Cu" "F.Mask" "F.Paste")
			(net "JTAG_CPLD3_TDI")
		)
		(pad "24" smd rect
			(at -7.750048 5.500116)
			(size 0.2794 1.4986)
			(layers "F.Cu" "F.Mask" "F.Paste")
			(net "JTAG_CPLD3_TCK")
		)
		(pad "25" smd rect
			(at -7.750048 5.999988)
			(size 0.2794 1.4986)
			(layers "F.Cu" "F.Mask" "F.Paste")
			(net "JTAG_CPLD3_TDO")
		)
		(pad "26" smd rect
			(at -5.999988 7.750048 270)
			(size 0.2794 1.4986)
			(layers "F.Cu" "F.Mask" "F.Paste")
			(net "UART_T7_NODE1_TXD")
		)
		(pad "27" smd rect
			(at -5.500116 7.750048 270)
			(size 0.2794 1.4986)
			(layers "F.Cu" "F.Mask" "F.Paste")
			(net "UART_T7_NODE1_RXD")
		)
		(pad "28" smd rect
			(at -4.99999 7.750048 270)
			(size 0.2794 1.4986)
			(layers "F.Cu" "F.Mask" "F.Paste")
			(net "UART_T7_NODE2_TXD")
		)
		(pad "29" smd rect
			(at -4.500118 7.750048 270)
			(size 0.2794 1.4986)
			(layers "F.Cu" "F.Mask" "F.Paste")
			(net "UART_T7_NODE2_RXD")
		)
		(pad "30" smd rect
			(at -3.999992 7.750048 270)
			(size 0.2794 1.4986)
			(layers "F.Cu" "F.Mask" "F.Paste")
			(net "CPLD_EXT_RST_N")
		)
		(pad "31" smd rect
			(at -3.50012 7.750048 270)
			(size 0.2794 1.4986)
			(layers "F.Cu" "F.Mask" "F.Paste")
			(net "P3V3_NODE1")
		)
		(pad "32" smd rect
			(at -2.999994 7.750048 270)
			(size 0.2794 1.4986)
			(layers "F.Cu" "F.Mask" "F.Paste")
			(net "GND")
		)
		(pad "33" smd rect
			(at -2.500122 7.750048 270)
			(size 0.2794 1.4986)
			(layers "F.Cu" "F.Mask" "F.Paste")
			(net "UART_T7_NODE3_TXD")
		)
		(pad "34" smd rect
			(at -1.999996 7.750048 270)
			(size 0.2794 1.4986)
			(layers "F.Cu" "F.Mask" "F.Paste")
			(net "UART_T7_NODE3_RXD")
		)
		(pad "35" smd rect
			(at -1.500124 7.750048 270)
			(size 0.2794 1.4986)
			(layers "F.Cu" "F.Mask" "F.Paste")
			(net "UART_T7_NODE4_TXD")
		)
		(pad "36" smd rect
			(at -0.999998 7.750048 270)
			(size 0.2794 1.4986)
			(layers "F.Cu" "F.Mask" "F.Paste")
			(net "UART_T7_NODE4_RXD")
		)
		(pad "37" smd rect
			(at -0.499872 7.750048 270)
			(size 0.2794 1.4986)
			(layers "F.Cu" "F.Mask" "F.Paste")
			(net "UART_T8_NODE1_TXD")
		)
		(pad "38" smd rect
			(at 0 7.750048 270)
			(size 0.2794 1.4986)
			(layers "F.Cu" "F.Mask" "F.Paste")
			(net "UART_T8_NODE1_RXD")
		)
		(pad "39" smd rect
			(at 0.499872 7.750048 270)
			(size 0.2794 1.4986)
			(layers "F.Cu" "F.Mask" "F.Paste")
			(net "UART_T8_NODE2_TXD")
		)
		(pad "40" smd rect
			(at 0.999998 7.750048 270)
			(size 0.2794 1.4986)
			(layers "F.Cu" "F.Mask" "F.Paste")
			(net "UART_T8_NODE2_RXD")
		)
		(pad "41" smd rect
			(at 1.500124 7.750048 270)
			(size 0.2794 1.4986)
			(layers "F.Cu" "F.Mask" "F.Paste")
			(net "UART_T8_NODE3_TXD")
		)
		(pad "42" smd rect
			(at 1.999996 7.750048 270)
			(size 0.2794 1.4986)
			(layers "F.Cu" "F.Mask" "F.Paste")
			(net "UART_T8_NODE3_RXD")
		)
		(pad "43" smd rect
			(at 2.500122 7.750048 270)
			(size 0.2794 1.4986)
			(layers "F.Cu" "F.Mask" "F.Paste")
			(net "CPLD_WDT1")
		)
		(pad "44" smd rect
			(at 2.999994 7.750048 270)
			(size 0.2794 1.4986)
			(layers "F.Cu" "F.Mask" "F.Paste")
			(net "CPLD_WDT2")
		)
		(pad "45" smd rect
			(at 3.50012 7.750048 270)
			(size 0.2794 1.4986)
			(layers "F.Cu" "F.Mask" "F.Paste")
			(net "P3V3_NODE1")
		)
		(pad "46" smd rect
			(at 3.999992 7.750048 270)
			(size 0.2794 1.4986)
			(layers "F.Cu" "F.Mask" "F.Paste")
			(net "GND")
		)
		(pad "47" smd rect
			(at 4.500118 7.750048 270)
			(size 0.2794 1.4986)
			(layers "F.Cu" "F.Mask" "F.Paste")
			(net "UART_T8_NODE4_TXD")
		)
		(pad "48" smd rect
			(at 4.99999 7.750048 270)
			(size 0.2794 1.4986)
			(layers "F.Cu" "F.Mask" "F.Paste")
			(net "UART_T8_NODE4_RXD")
		)
		(pad "49" smd rect
			(at 5.500116 7.750048 270)
			(size 0.2794 1.4986)
			(layers "F.Cu" "F.Mask" "F.Paste")
			(net "CPLD3_RSV1")
		)
		(pad "50" smd rect
			(at 5.999988 7.750048 270)
			(size 0.2794 1.4986)
			(layers "F.Cu" "F.Mask" "F.Paste")
			(net "CPLD3_RSV2")
		)
		(pad "51" smd rect
			(at 7.750048 5.999988)
			(size 0.2794 1.4986)
			(layers "F.Cu" "F.Mask" "F.Paste")
			(net "CPLD3_RSV3")
		)
		(pad "52" smd rect
			(at 7.750048 5.500116)
			(size 0.2794 1.4986)
			(layers "F.Cu" "F.Mask" "F.Paste")
			(net "UART_T9_NODE1_TXD")
		)
		(pad "53" smd rect
			(at 7.750048 4.99999)
			(size 0.2794 1.4986)
			(layers "F.Cu" "F.Mask" "F.Paste")
			(net "UART_T9_NODE1_RXD")
		)
		(pad "54" smd rect
			(at 7.750048 4.500118)
			(size 0.2794 1.4986)
			(layers "F.Cu" "F.Mask" "F.Paste")
			(net "UART_T9_NODE2_TXD")
		)
		(pad "55" smd rect
			(at 7.750048 3.999992)
			(size 0.2794 1.4986)
			(layers "F.Cu" "F.Mask" "F.Paste")
			(net "UART_T9_NODE2_RXD")
		)
		(pad "56" smd rect
			(at 7.750048 3.50012)
			(size 0.2794 1.4986)
			(layers "F.Cu" "F.Mask" "F.Paste")
			(net "UART_T9_NODE3_TXD")
		)
		(pad "57" smd rect
			(at 7.750048 2.999994)
			(size 0.2794 1.4986)
			(layers "F.Cu" "F.Mask" "F.Paste")
			(net "UART_T9_NODE3_RXD")
		)
		(pad "58" smd rect
			(at 7.750048 2.500122)
			(size 0.2794 1.4986)
			(layers "F.Cu" "F.Mask" "F.Paste")
			(net "TACKOVER_EN_N")
		)
		(pad "59" smd rect
			(at 7.750048 1.999996)
			(size 0.2794 1.4986)
			(layers "F.Cu" "F.Mask" "F.Paste")
			(net "P3V3_NODE1")
		)
		(pad "60" smd rect
			(at 7.750048 1.500124)
			(size 0.2794 1.4986)
			(layers "F.Cu" "F.Mask" "F.Paste")
			(net "GND")
		)
		(pad "61" smd rect
			(at 7.750048 0.999998)
			(size 0.2794 1.4986)
			(layers "F.Cu" "F.Mask" "F.Paste")
			(net "CMC_CPU_RST_N")
		)
		(pad "62" smd rect
			(at 7.750048 0.499872)
			(size 0.2794 1.4986)
			(layers "F.Cu" "F.Mask" "F.Paste")
			(net "UART_RI_P3_BUFFER_N")
		)
		(pad "63" smd rect
			(at 7.750048 0)
			(size 0.2794 1.4986)
			(layers "F.Cu" "F.Mask" "F.Paste")
			(net "P3V3_NODE1")
		)
		(pad "64" smd rect
			(at 7.750048 -0.499872)
			(size 0.2794 1.4986)
			(layers "F.Cu" "F.Mask" "F.Paste")
			(net "CLK_33K_CPLD23")
		)
		(pad "65" smd rect
			(at 7.750048 -0.999998)
			(size 0.2794 1.4986)
			(layers "F.Cu" "F.Mask" "F.Paste")
			(net "GND")
		)
		(pad "66" smd rect
			(at 7.750048 -1.500124)
			(size 0.2794 1.4986)
			(layers "F.Cu" "F.Mask" "F.Paste")
			(net "UART_T9_NODE4_TXD")
		)
		(pad "67" smd rect
			(at 7.750048 -1.999996)
			(size 0.2794 1.4986)
			(layers "F.Cu" "F.Mask" "F.Paste")
			(net "UART_T9_NODE4_RXD")
		)
		(pad "68" smd rect
			(at 7.750048 -2.500122)
			(size 0.2794 1.4986)
			(layers "F.Cu" "F.Mask" "F.Paste")
			(net "UART_T10_NODE1_TXD")
		)
		(pad "69" smd rect
			(at 7.750048 -2.999994)
			(size 0.2794 1.4986)
			(layers "F.Cu" "F.Mask" "F.Paste")
			(net "UART_T10_NODE1_RXD")
		)
		(pad "70" smd rect
			(at 7.750048 -3.50012)
			(size 0.2794 1.4986)
			(layers "F.Cu" "F.Mask" "F.Paste")
			(net "UART_T10_NODE2_TXD")
		)
		(pad "71" smd rect
			(at 7.750048 -3.999992)
			(size 0.2794 1.4986)
			(layers "F.Cu" "F.Mask" "F.Paste")
			(net "UART_T10_NODE2_RXD")
		)
		(pad "72" smd rect
			(at 7.750048 -4.500118)
			(size 0.2794 1.4986)
			(layers "F.Cu" "F.Mask" "F.Paste")
			(net "UART_T10_NODE3_TXD")
		)
		(pad "73" smd rect
			(at 7.750048 -4.99999)
			(size 0.2794 1.4986)
			(layers "F.Cu" "F.Mask" "F.Paste")
			(net "UART_T10_NODE3_RXD")
		)
		(pad "74" smd rect
			(at 7.750048 -5.500116)
			(size 0.2794 1.4986)
			(layers "F.Cu" "F.Mask" "F.Paste")
			(net "UART_T10_NODE4_TXD")
		)
		(pad "75" smd rect
			(at 7.750048 -5.999988)
			(size 0.2794 1.4986)
			(layers "F.Cu" "F.Mask" "F.Paste")
			(net "UART_T10_NODE4_RXD")
		)
		(pad "76" smd rect
			(at 5.999988 -7.750048 270)
			(size 0.2794 1.4986)
			(layers "F.Cu" "F.Mask" "F.Paste")
			(net "UART_T11_NODE1_TXD")
		)
		(pad "77" smd rect
			(at 5.500116 -7.750048 270)
			(size 0.2794 1.4986)
			(layers "F.Cu" "F.Mask" "F.Paste")
			(net "UART_T11_NODE1_RXD")
		)
		(pad "78" smd rect
			(at 4.99999 -7.750048 270)
			(size 0.2794 1.4986)
			(layers "F.Cu" "F.Mask" "F.Paste")
			(net "UART_RTS_P3_N")
		)
		(pad "79" smd rect
			(at 4.500118 -7.750048 270)
			(size 0.2794 1.4986)
			(layers "F.Cu" "F.Mask" "F.Paste")
			(net "GND")
		)
		(pad "80" smd rect
			(at 3.999992 -7.750048 270)
			(size 0.2794 1.4986)
			(layers "F.Cu" "F.Mask" "F.Paste")
			(net "P3V3_NODE1")
		)
		(pad "81" smd rect
			(at 3.50012 -7.750048 270)
			(size 0.2794 1.4986)
			(layers "F.Cu" "F.Mask" "F.Paste")
			(net "UART_T11_NODE2_TXD")
		)
		(pad "82" smd rect
			(at 2.999994 -7.750048 270)
			(size 0.2794 1.4986)
			(layers "F.Cu" "F.Mask" "F.Paste")
			(net "UART_T11_NODE2_RXD")
		)
		(pad "83" smd rect
			(at 2.500122 -7.750048 270)
			(size 0.2794 1.4986)
			(layers "F.Cu" "F.Mask" "F.Paste")
			(net "UART_T11_NODE3_TXD")
		)
		(pad "84" smd rect
			(at 1.999996 -7.750048 270)
			(size 0.2794 1.4986)
			(layers "F.Cu" "F.Mask" "F.Paste")
			(net "UART_T11_NODE3_RXD")
		)
		(pad "85" smd rect
			(at 1.500124 -7.750048 270)
			(size 0.2794 1.4986)
			(layers "F.Cu" "F.Mask" "F.Paste")
			(net "UART_T11_NODE4_TXD")
		)
		(pad "86" smd rect
			(at 0.999998 -7.750048 270)
			(size 0.2794 1.4986)
			(layers "F.Cu" "F.Mask" "F.Paste")
			(net "UART_T11_NODE4_RXD")
		)
		(pad "87" smd rect
			(at 0.499872 -7.750048 270)
			(size 0.2794 1.4986)
			(layers "F.Cu" "F.Mask" "F.Paste")
			(net "UART_T12_NODE1_TXD")
		)
		(pad "88" smd rect
			(at 0 -7.750048 270)
			(size 0.2794 1.4986)
			(layers "F.Cu" "F.Mask" "F.Paste")
			(net "UART_T12_NODE1_RXD")
		)
		(pad "89" smd rect
			(at -0.499872 -7.750048 270)
			(size 0.2794 1.4986)
			(layers "F.Cu" "F.Mask" "F.Paste")
			(net "UART_T12_NODE2_TXD")
		)
		(pad "90" smd rect
			(at -0.999998 -7.750048 270)
			(size 0.2794 1.4986)
			(layers "F.Cu" "F.Mask" "F.Paste")
			(net "UART_T12_NODE2_RXD")
		)
		(pad "91" smd rect
			(at -1.500124 -7.750048 270)
			(size 0.2794 1.4986)
			(layers "F.Cu" "F.Mask" "F.Paste")
			(net "UART_T12_NODE3_TXD")
		)
		(pad "92" smd rect
			(at -1.999996 -7.750048 270)
			(size 0.2794 1.4986)
			(layers "F.Cu" "F.Mask" "F.Paste")
			(net "UART_T12_NODE3_RXD")
		)
		(pad "93" smd rect
			(at -2.500122 -7.750048 270)
			(size 0.2794 1.4986)
			(layers "F.Cu" "F.Mask" "F.Paste")
			(net "GND")
		)
		(pad "94" smd rect
			(at -2.999994 -7.750048 270)
			(size 0.2794 1.4986)
			(layers "F.Cu" "F.Mask" "F.Paste")
			(net "P3V3_NODE1")
		)
		(pad "95" smd rect
			(at -3.50012 -7.750048 270)
			(size 0.2794 1.4986)
			(layers "F.Cu" "F.Mask" "F.Paste")
			(net "UART_T12_NODE4_TXD")
		)
		(pad "96" smd rect
			(at -3.999992 -7.750048 270)
			(size 0.2794 1.4986)
			(layers "F.Cu" "F.Mask" "F.Paste")
			(net "UART_T12_NODE4_RXD")
		)
		(pad "97" smd rect
			(at -4.500118 -7.750048 270)
			(size 0.2794 1.4986)
			(layers "F.Cu" "F.Mask" "F.Paste")
			(net "CPLD_UART_RTS_P3_N")
		)
		(pad "98" smd rect
			(at -4.99999 -7.750048 270)
			(size 0.2794 1.4986)
			(layers "F.Cu" "F.Mask" "F.Paste")
			(net "CPLD_UART_RI_P3_N")
		)
		(pad "99" smd rect
			(at -5.500116 -7.750048 270)
			(size 0.2794 1.4986)
			(layers "F.Cu" "F.Mask" "F.Paste")
			(net "CPLD_UART_RX_P3")
		)
		(pad "100" smd rect
			(at -5.999988 -7.750048 270)
			(size 0.2794 1.4986)
			(layers "F.Cu" "F.Mask" "F.Paste")
			(net "CPLD_UART_TX_P3")
		)
	)
)
